FILE_TYPE = MULTI_PHYS_TABLE;

PART 'DS125BR111RTWR'

{========================================================================================}
:VALUE            | PART_TYPE | MATERIAL | PART_NUMBER    = STANDARD    | LIFECYCLE      | PART_NUMBER   | JEDEC_TYPE            | DESCRIPTION                         | MANUFTR | MANUF_PN         | RD_CMPLS_LVL | CMPLS_LVL | FROM_PJ    | CLASS | DIP_SMD | DATA                     | EE_CHECK_LIST | FP_ECN | PSL | CREATOR | STATUS | MSD | ESD_CDM | ESD_HBM | ESD_MM | PIN_LENGTH_SHORT_PIN | PIN_LENGTH_LONG_PIN | CREATEDAY  ;
{========================================================================================}
 'DS125BR111RTWR' | 'SMLF'    | 'IC'     | 'AL000125003'(!) = ''               | ''               | 'AL000125003' |'WQFN24_TH_0-5_4X4XA'| 'IC OTHER(24P)DS125BR111RTWR(WQFN)' | 'TIC'   | 'DS125BR111RTWR' | 'EP(V1)'     | 'EP(V1)'  | 'F0T-IVES' | 'IC'  | ''      | 'TIC_DS125BR111RTWR.pdf' | ''            | ''     | ''  | ''      | ''     | ''  | ''      | ''      | ''     | '0 MILS'             | '0 MILS'            | '20220331'
 'DS125BR111RTWR' | 'SMLF'    | 'EMPTY'  | 'AL000125003'(!) = ''               | ''               | 'AL000125003' |'WQFN24_TH_0-5_4X4XA'| 'IC OTHER(24P)DS125BR111RTWR(WQFN)' | 'TIC'   | 'DS125BR111RTWR' | 'EP(V1)'     | 'EP(V1)'  | 'F0T-IVES' | 'IC'  | ''      | 'TIC_DS125BR111RTWR.pdf' | ''            | ''     | ''  | ''      | ''     | ''  | ''      | ''      | ''     | '0 MILS'             | '0 MILS'            | '20220331'

END_PART

END.

